# S9S_MB_2U (Grand Teton) — schematic netlist excerpt (pin names and nets, part order shuffled) for the footprints in the layout excerpt that follows; sources: Cadence DE-HDL packaged netlist, KiCad conversion of 03242023_DA0F0TMBIJ0_F0T_Motherboard_J_brd_V01_OCP.brd

PL18  Q_INDUCTOR  130NH/106A IND  pkg SMLF  page 289 : \1\ = SW_PVCCFA_EHV_FIVRA_CPU1_SW1 ; \2\ = PVCCFA_EHV_FIVRA_CPU1
R4755  Q_RES  33.2 1% CHIP  pkg 0402LF  page 164 : A = OCP_V3_2_AUX_PWR_PLD_EN ; B = OCP_V3_2_AUX_PWR_PLD_EN_R

(kicad_pcb
	(version 20260206)
	(generator "pcbnew")
	(generator_version "10.0")
	(general
		(thickness 1.6)
		(legacy_teardrops no)
	)
	(paper "A4")
	(title_block
		(title "03242023_DA0F0TMBIJ0_F0T_Motherboard_J_brd_V01_OCP.brd")
		(comment 1 "Grand Teton / footprints 3463-3464 of 6105")
	)
	(layers
		(0 "F.Cu" signal "TOP")
		(4 "In1.Cu" signal "GND")
		(6 "In2.Cu" signal "IN1")
		(8 "In3.Cu" signal "GND1")
		(10 "In4.Cu" signal "IN2")
		(12 "In5.Cu" signal "GND2")
		(14 "In6.Cu" signal "IN3")
		(16 "In7.Cu" signal "GND3")
		(18 "In8.Cu" signal "VCC")
		(20 "In9.Cu" signal "VCC1")
		(22 "In10.Cu" signal "GND4")
		(24 "In11.Cu" signal "IN4")
		(26 "In12.Cu" signal "GND5")
		(28 "In13.Cu" signal "IN5")
		(30 "In14.Cu" signal "GND6")
		(32 "In15.Cu" signal "IN6")
		(34 "In16.Cu" signal "GND7")
		(2 "B.Cu" signal "BOTTOM")
		(9 "F.Adhes" user "F.Adhesive")
		(11 "B.Adhes" user "B.Adhesive")
		(13 "F.Paste" user "Package Geometry/Pastemask Top")
		(15 "B.Paste" user "Package Geometry/Pastemask Bottom")
		(5 "F.SilkS" user "Ref Des/Silkscreen Top")
		(7 "B.SilkS" user "Ref Des/Silkscreen Bottom")
		(1 "F.Mask" user "Board Geometry/Soldermask Top")
		(3 "B.Mask" user "Board Geometry/Soldermask Bottom")
		(17 "Dwgs.User" user "User.Drawings")
		(19 "Cmts.User" user "User.Comments")
		(21 "Eco1.User" user "User.Eco1")
		(23 "Eco2.User" user "User.Eco2")
		(25 "Edge.Cuts" user "Board Geometry/Outline")
		(27 "Margin" user)
		(31 "F.CrtYd" user "Package Geometry/Place Bound Top")
		(29 "B.CrtYd" user "Package Geometry/Place Bound Bottom")
		(35 "F.Fab" user "Ref Des/Assembly Top")
		(33 "B.Fab" user "Ref Des/Assembly Bottom")
	)
	(footprint ""
		(layer "F.Cu")
		(at 136.3853 -112.363504)
		(property "Reference" "R4755"
			(at 0 0 0)
			(layer "F.SilkS")
			(hide yes)
			(effects
				(font
					(size 1.27 1.27)
				)
			)
		)
		(property "Value" ""
			(at 0 0 0)
			(layer "F.Fab")
			(effects
				(font
					(size 1.27 1.27)
				)
			)
		)
		(duplicate_pad_numbers_are_jumpers no)
		(fp_line
			(start -0.7874 -0.4064)
			(end 0.7874 -0.4064)
			(stroke
				(width 0.1524)
				(type default)
			)
			(layer "F.SilkS")
		)
		(fp_line
			(start -0.7874 0.4064)
			(end -0.7874 -0.4064)
			(stroke
				(width 0.1524)
				(type default)
			)
			(layer "F.SilkS")
		)
		(fp_line
			(start 0.7874 -0.4064)
			(end 0.7874 0.4064)
			(stroke
				(width 0.1524)
				(type default)
			)
			(layer "F.SilkS")
		)
		(fp_line
			(start 0.7874 0.4064)
			(end -0.7874 0.4064)
			(stroke
				(width 0.1524)
				(type default)
			)
			(layer "F.SilkS")
		)
		(fp_line
			(start -0.67945 -0.305054)
			(end -0.12065 -0.305054)
			(stroke
				(width 0.1)
				(type default)
			)
			(layer "F.Fab")
		)
		(fp_line
			(start -0.67945 0.3048)
			(end -0.67945 -0.305054)
			(stroke
				(width 0.1)
				(type default)
			)
			(layer "F.Fab")
		)
		(fp_line
			(start -0.12065 -0.305054)
			(end -0.12065 -0.2794)
			(stroke
				(width 0.1)
				(type default)
			)
			(layer "F.Fab")
		)
		(fp_line
			(start -0.12065 -0.2794)
			(end 0.12065 -0.2794)
			(stroke
				(width 0.1)
				(type default)
			)
			(layer "F.Fab")
		)
		(fp_line
			(start -0.12065 0.2794)
			(end -0.12065 0.3048)
			(stroke
				(width 0.1)
				(type default)
			)
			(layer "F.Fab")
		)
		(fp_line
			(start -0.12065 0.3048)
			(end -0.67945 0.3048)
			(stroke
				(width 0.1)
				(type default)
			)
			(layer "F.Fab")
		)
		(fp_line
			(start 0.120396 0.2794)
			(end -0.12065 0.2794)
			(stroke
				(width 0.1)
				(type default)
			)
			(layer "F.Fab")
		)
		(fp_line
			(start 0.120396 0.3048)
			(end 0.120396 0.2794)
			(stroke
				(width 0.1)
				(type default)
			)
			(layer "F.Fab")
		)
		(fp_line
			(start 0.12065 -0.3048)
			(end 0.67945 -0.3048)
			(stroke
				(width 0.1)
				(type default)
			)
			(layer "F.Fab")
		)
		(fp_line
			(start 0.12065 -0.2794)
			(end 0.12065 -0.3048)
			(stroke
				(width 0.1)
				(type default)
			)
			(layer "F.Fab")
		)
		(fp_line
			(start 0.67945 -0.3048)
			(end 0.67945 0.3048)
			(stroke
				(width 0.1)
				(type default)
			)
			(layer "F.Fab")
		)
		(fp_line
			(start 0.67945 0.3048)
			(end 0.120396 0.3048)
			(stroke
				(width 0.1)
				(type default)
			)
			(layer "F.Fab")
		)
		(pad "1" smd circle
			(at -0.40005 0)
			(size 0 0)
			(layers "F.Cu" "F.Mask" "F.Paste")
			(net "OCP_V3_2_AUX_PWR_PLD_EN")
		)
		(pad "2" smd circle
			(at 0.40005 0)
			(size 0 0)
			(layers "F.Cu" "F.Mask" "F.Paste")
			(net "OCP_V3_2_AUX_PWR_PLD_EN_R")
		)
	)
	(footprint ""
		(layer "F.Cu")
		(at 172.033184 -344.7796 -90)
		(property "Reference" "PL18"
			(at -1.768348 -4.904486 90)
			(unlocked yes)
			(layer "F.SilkS")
			(effects
				(font
					(size 0.7874 0.5842)
					(thickness 0.1524)
				)
				(justify left)
			)
		)
		(property "Value" ""
			(at 0 0 270)
			(layer "F.Fab")
			(effects
				(font
					(size 1.27 1.27)
				)
			)
		)
		(duplicate_pad_numbers_are_jumpers no)
		(fp_line
			(start -4.99999 3.750056)
			(end -4.99999 2.2479)
			(stroke
				(width 0.1524)
				(type default)
			)
			(layer "F.SilkS")
		)
		(fp_line
			(start 0 3.750056)
			(end -4.99999 3.750056)
			(stroke
				(width 0.1524)
				(type default)
			)
			(layer "F.SilkS")
		)
		(fp_line
			(start 4.99999 3.750056)
			(end 0 3.750056)
			(stroke
				(width 0.1524)
				(type default)
			)
			(layer "F.SilkS")
		)
		(fp_line
			(start 4.99999 2.2352)
			(end 4.99999 3.750056)
			(stroke
				(width 0.1524)
				(type default)
			)
			(layer "F.SilkS")
		)
		(fp_line
			(start -4.99999 -2.2479)
			(end -4.99999 -3.750056)
			(stroke
				(width 0.1524)
				(type default)
			)
			(layer "F.SilkS")
		)
		(fp_line
			(start -4.99999 -3.750056)
			(end 4.99999 -3.750056)
			(stroke
				(width 0.1524)
				(type default)
			)
			(layer "F.SilkS")
		)
		(fp_line
			(start 4.99999 -3.750056)
			(end 4.99999 -2.2479)
			(stroke
				(width 0.1524)
				(type default)
			)
			(layer "F.SilkS")
		)
		(fp_line
			(start -4.99999 3.750056)
			(end -4.99999 -3.750056)
			(stroke
				(width 0.1)
				(type default)
			)
			(layer "F.Fab")
		)
		(fp_line
			(start 0 3.750056)
			(end -4.99999 3.750056)
			(stroke
				(width 0.1)
				(type default)
			)
			(layer "F.Fab")
		)
		(fp_line
			(start 4.99999 3.750056)
			(end 0 3.750056)
			(stroke
				(width 0.1)
				(type default)
			)
			(layer "F.Fab")
		)
		(fp_line
			(start -4.99999 -3.750056)
			(end 4.99999 -3.750056)
			(stroke
				(width 0.1)
				(type default)
			)
			(layer "F.Fab")
		)
		(fp_line
			(start 4.99999 -3.750056)
			(end 4.99999 3.750056)
			(stroke
				(width 0.1)
				(type default)
			)
			(layer "F.Fab")
		)
		(pad "1" smd rect
			(at -3.299968 0 270)
			(size 3.302 4.2164)
			(layers "F.Cu" "F.Mask" "F.Paste")
			(net "SW_PVCCFA_EHV_FIVRA_CPU1_SW1")
		)
		(pad "2" smd rect
			(at 3.299968 0 270)
			(size 3.302 4.2164)
			(layers "F.Cu" "F.Mask" "F.Paste")
			(net "PVCCFA_EHV_FIVRA_CPU1")
		)
	)
)
